# T6G (Grand Teton) — schematic netlist excerpt (pin names and nets, part order shuffled) for the footprints in the layout excerpt that follows; sources: Cadence DE-HDL packaged netlist, KiCad conversion of 04192023_DAF0TMB3IC0_F0TG_MB_C_brd_V02_OCP.brd

C1505  Q_CAP  0.1UF 16V 10% X7R  pkg C0402  page 172 : A = PVDD18_S5_P0 ; B = GND
R8125  Q_RES  1K 1% CHIP  pkg 0402LF  page 268 : A = P3V3_AUX ; B = IRQ_UV_DETECT_N

(kicad_pcb
	(version 20260206)
	(generator "pcbnew")
	(generator_version "10.0")
	(general
		(thickness 1.6)
		(legacy_teardrops no)
	)
	(paper "A4")
	(title_block
		(title "04192023_DAF0TMB3IC0_F0TG_MB_C_brd_V02_OCP.brd")
		(comment 1 "Grand Teton / footprints 2070-2071 of 8354")
	)
	(layers
		(0 "F.Cu" signal "TOP")
		(4 "In1.Cu" signal "GND")
		(6 "In2.Cu" signal "IN1")
		(8 "In3.Cu" signal "GND1")
		(10 "In4.Cu" signal "IN2")
		(12 "In5.Cu" signal "GND2")
		(14 "In6.Cu" signal "IN3")
		(16 "In7.Cu" signal "GND3")
		(18 "In8.Cu" signal "VCC")
		(20 "In9.Cu" signal "VCC1")
		(22 "In10.Cu" signal "GND4")
		(24 "In11.Cu" signal "IN4")
		(26 "In12.Cu" signal "GND5")
		(28 "In13.Cu" signal "IN5")
		(30 "In14.Cu" signal "GND6")
		(32 "In15.Cu" signal "IN6")
		(34 "In16.Cu" signal "GND7")
		(2 "B.Cu" signal "BOTTOM")
		(9 "F.Adhes" user "F.Adhesive")
		(11 "B.Adhes" user "B.Adhesive")
		(13 "F.Paste" user "Package Geometry/Pastemask Top")
		(15 "B.Paste" user "Package Geometry/Pastemask Bottom")
		(5 "F.SilkS" user "Ref Des/Silkscreen Top")
		(7 "B.SilkS" user "Ref Des/Silkscreen Bottom")
		(1 "F.Mask" user "Board Geometry/Soldermask Top")
		(3 "B.Mask" user "Board Geometry/Soldermask Bottom")
		(17 "Dwgs.User" user "User.Drawings")
		(19 "Cmts.User" user "User.Comments")
		(21 "Eco1.User" user "User.Eco1")
		(23 "Eco2.User" user "User.Eco2")
		(25 "Edge.Cuts" user "Board Geometry/Outline")
		(27 "Margin" user)
		(31 "F.CrtYd" user "Package Geometry/Place Bound Top")
		(29 "B.CrtYd" user "Package Geometry/Place Bound Bottom")
		(35 "F.Fab" user "Ref Des/Assembly Top")
		(33 "B.Fab" user "Ref Des/Assembly Bottom")
	)
	(footprint ""
		(layer "F.Cu")
		(at 145.773394 -54.913784 -90)
		(property "Reference" "C1505"
			(at 0 0 270)
			(layer "F.SilkS")
			(hide yes)
			(effects
				(font
					(size 1.27 1.27)
				)
			)
		)
		(property "Value" ""
			(at 0 0 270)
			(layer "F.Fab")
			(effects
				(font
					(size 1.27 1.27)
				)
			)
		)
		(duplicate_pad_numbers_are_jumpers no)
		(fp_line
			(start -0.7874 0.4064)
			(end -0.7874 -0.4064)
			(stroke
				(width 0.1524)
				(type default)
			)
			(layer "F.SilkS")
		)
		(fp_line
			(start 0.7874 0.4064)
			(end -0.7874 0.4064)
			(stroke
				(width 0.1524)
				(type default)
			)
			(layer "F.SilkS")
		)
		(fp_line
			(start -0.7874 -0.4064)
			(end 0.7874 -0.4064)
			(stroke
				(width 0.1524)
				(type default)
			)
			(layer "F.SilkS")
		)
		(fp_line
			(start 0.7874 -0.4064)
			(end 0.7874 0.4064)
			(stroke
				(width 0.1524)
				(type default)
			)
			(layer "F.SilkS")
		)
		(fp_line
			(start -0.67945 0.3048)
			(end -0.67945 -0.305054)
			(stroke
				(width 0.1)
				(type default)
			)
			(layer "F.Fab")
		)
		(fp_line
			(start -0.12065 0.3048)
			(end -0.67945 0.3048)
			(stroke
				(width 0.1)
				(type default)
			)
			(layer "F.Fab")
		)
		(fp_line
			(start 0.120396 0.3048)
			(end 0.120396 0.2794)
			(stroke
				(width 0.1)
				(type default)
			)
			(layer "F.Fab")
		)
		(fp_line
			(start 0.67945 0.3048)
			(end 0.120396 0.3048)
			(stroke
				(width 0.1)
				(type default)
			)
			(layer "F.Fab")
		)
		(fp_line
			(start -0.12065 0.2794)
			(end -0.12065 0.3048)
			(stroke
				(width 0.1)
				(type default)
			)
			(layer "F.Fab")
		)
		(fp_line
			(start 0.120396 0.2794)
			(end -0.12065 0.2794)
			(stroke
				(width 0.1)
				(type default)
			)
			(layer "F.Fab")
		)
		(fp_line
			(start -0.12065 -0.2794)
			(end 0.12065 -0.2794)
			(stroke
				(width 0.1)
				(type default)
			)
			(layer "F.Fab")
		)
		(fp_line
			(start 0.12065 -0.2794)
			(end 0.12065 -0.3048)
			(stroke
				(width 0.1)
				(type default)
			)
			(layer "F.Fab")
		)
		(fp_line
			(start 0.12065 -0.3048)
			(end 0.67945 -0.3048)
			(stroke
				(width 0.1)
				(type default)
			)
			(layer "F.Fab")
		)
		(fp_line
			(start 0.67945 -0.3048)
			(end 0.67945 0.3048)
			(stroke
				(width 0.1)
				(type default)
			)
			(layer "F.Fab")
		)
		(fp_line
			(start -0.67945 -0.305054)
			(end -0.12065 -0.305054)
			(stroke
				(width 0.1)
				(type default)
			)
			(layer "F.Fab")
		)
		(fp_line
			(start -0.12065 -0.305054)
			(end -0.12065 -0.2794)
			(stroke
				(width 0.1)
				(type default)
			)
			(layer "F.Fab")
		)
		(pad "1" smd circle
			(at -0.40005 0 270)
			(size 0 0)
			(layers "F.Cu" "F.Mask" "F.Paste")
			(net "PVDD18_S5_P0")
		)
		(pad "2" smd circle
			(at 0.40005 0 270)
			(size 0 0)
			(layers "F.Cu" "F.Mask" "F.Paste")
			(net "GND")
		)
	)
	(footprint ""
		(layer "F.Cu")
		(at 145.161 -119.761)
		(property "Reference" "R8125"
			(at 0 0 0)
			(layer "F.SilkS")
			(hide yes)
			(effects
				(font
					(size 1.27 1.27)
				)
			)
		)
		(property "Value" ""
			(at 0 0 0)
			(layer "F.Fab")
			(effects
				(font
					(size 1.27 1.27)
				)
			)
		)
		(duplicate_pad_numbers_are_jumpers no)
		(fp_line
			(start -0.7874 -0.4064)
			(end 0.7874 -0.4064)
			(stroke
				(width 0.1524)
				(type default)
			)
			(layer "F.SilkS")
		)
		(fp_line
			(start -0.7874 0.4064)
			(end -0.7874 -0.4064)
			(stroke
				(width 0.1524)
				(type default)
			)
			(layer "F.SilkS")
		)
		(fp_line
			(start 0.7874 -0.4064)
			(end 0.7874 0.4064)
			(stroke
				(width 0.1524)
				(type default)
			)
			(layer "F.SilkS")
		)
		(fp_line
			(start 0.7874 0.4064)
			(end -0.7874 0.4064)
			(stroke
				(width 0.1524)
				(type default)
			)
			(layer "F.SilkS")
		)
		(fp_line
			(start -0.67945 -0.305054)
			(end -0.12065 -0.305054)
			(stroke
				(width 0.1)
				(type default)
			)
			(layer "F.Fab")
		)
		(fp_line
			(start -0.67945 0.3048)
			(end -0.67945 -0.305054)
			(stroke
				(width 0.1)
				(type default)
			)
			(layer "F.Fab")
		)
		(fp_line
			(start -0.12065 -0.305054)
			(end -0.12065 -0.2794)
			(stroke
				(width 0.1)
				(type default)
			)
			(layer "F.Fab")
		)
		(fp_line
			(start -0.12065 -0.2794)
			(end 0.12065 -0.2794)
			(stroke
				(width 0.1)
				(type default)
			)
			(layer "F.Fab")
		)
		(fp_line
			(start -0.12065 0.2794)
			(end -0.12065 0.3048)
			(stroke
				(width 0.1)
				(type default)
			)
			(layer "F.Fab")
		)
		(fp_line
			(start -0.12065 0.3048)
			(end -0.67945 0.3048)
			(stroke
				(width 0.1)
				(type default)
			)
			(layer "F.Fab")
		)
		(fp_line
			(start 0.120396 0.2794)
			(end -0.12065 0.2794)
			(stroke
				(width 0.1)
				(type default)
			)
			(layer "F.Fab")
		)
		(fp_line
			(start 0.120396 0.3048)
			(end 0.120396 0.2794)
			(stroke
				(width 0.1)
				(type default)
			)
			(layer "F.Fab")
		)
		(fp_line
			(start 0.12065 -0.3048)
			(end 0.67945 -0.3048)
			(stroke
				(width 0.1)
				(type default)
			)
			(layer "F.Fab")
		)
		(fp_line
			(start 0.12065 -0.2794)
			(end 0.12065 -0.3048)
			(stroke
				(width 0.1)
				(type default)
			)
			(layer "F.Fab")
		)
		(fp_line
			(start 0.67945 -0.3048)
			(end 0.67945 0.3048)
			(stroke
				(width 0.1)
				(type default)
			)
			(layer "F.Fab")
		)
		(fp_line
			(start 0.67945 0.3048)
			(end 0.120396 0.3048)
			(stroke
				(width 0.1)
				(type default)
			)
			(layer "F.Fab")
		)
		(pad "1" smd circle
			(at -0.40005 0)
			(size 0 0)
			(layers "F.Cu" "F.Mask" "F.Paste")
			(net "P3V3_AUX")
		)
		(pad "2" smd circle
			(at 0.40005 0)
			(size 0 0)
			(layers "F.Cu" "F.Mask" "F.Paste")
			(net "IRQ_UV_DETECT_N")
		)
	)
)
